(kicad_pcb
	(version 20260206)
	(generator "pcbnew")
	(generator_version "10.0")
	(general
		(thickness 1.6)
		(legacy_teardrops no)
	)
	(paper "A4")
	(title_block
		(title "04192023_DAF0TMB3IC0_F0TG_MB_C_brd_V02_OCP.brd")
		(comment 1 "Grand Teton / footprint 2783 of 8354 (U26), pads 5232-5340 of 6102")
	)
	(layers
		(0 "F.Cu" signal "TOP")
		(4 "In1.Cu" signal "GND")
		(6 "In2.Cu" signal "IN1")
		(8 "In3.Cu" signal "GND1")
		(10 "In4.Cu" signal "IN2")
		(12 "In5.Cu" signal "GND2")
		(14 "In6.Cu" signal "IN3")
		(16 "In7.Cu" signal "GND3")
		(18 "In8.Cu" signal "VCC")
		(20 "In9.Cu" signal "VCC1")
		(22 "In10.Cu" signal "GND4")
		(24 "In11.Cu" signal "IN4")
		(26 "In12.Cu" signal "GND5")
		(28 "In13.Cu" signal "IN5")
		(30 "In14.Cu" signal "GND6")
		(32 "In15.Cu" signal "IN6")
		(34 "In16.Cu" signal "GND7")
		(2 "B.Cu" signal "BOTTOM")
		(9 "F.Adhes" user "F.Adhesive")
		(11 "B.Adhes" user "B.Adhesive")
		(13 "F.Paste" user "Package Geometry/Pastemask Top")
		(15 "B.Paste" user "Package Geometry/Pastemask Bottom")
		(5 "F.SilkS" user "Ref Des/Silkscreen Top")
		(7 "B.SilkS" user "Ref Des/Silkscreen Bottom")
		(1 "F.Mask" user "Board Geometry/Soldermask Top")
		(3 "B.Mask" user "Board Geometry/Soldermask Bottom")
		(17 "Dwgs.User" user "User.Drawings")
		(19 "Cmts.User" user "User.Comments")
		(21 "Eco1.User" user "User.Eco1")
		(23 "Eco2.User" user "User.Eco2")
		(25 "Edge.Cuts" user "Board Geometry/Outline")
		(27 "Margin" user)
		(31 "F.CrtYd" user "Package Geometry/Place Bound Top")
		(29 "B.CrtYd" user "Package Geometry/Place Bound Bottom")
		(35 "F.Fab" user "Ref Des/Assembly Top")
		(33 "B.Fab" user "Ref Des/Assembly Bottom")
	)
	(footprint ""
		(layer "F.Cu")
		(at 111.927894 -258.880356 180)
		(property "Reference" "U26"
			(at -45.05579 -61.794136 0)
			(unlocked yes)
			(layer "F.SilkS")
			(effects
				(font
					(size 0.7874 0.5842)
					(thickness 0.1524)
				)
			)
		)
		(property "Value" ""
			(at 0 0 180)
			(layer "F.Fab")
			(effects
				(font
					(size 1.27 1.27)
				)
			)
		)
		(duplicate_pad_numbers_are_jumpers no)
		(pad "H68" smd circle
			(at 28.349956 -31.139892 180)
			(size 0.450088 0.450088)
			(layers "F.Cu" "F.Mask" "F.Paste")
			(net "GND")
		)
		(pad "H69" smd circle
			(at 29.29001 -31.139892 180)
			(size 0.450088 0.450088)
			(layers "F.Cu" "F.Mask" "F.Paste")
			(net "M_E_CPU1_SA_DQS_DN<5>")
		)
		(pad "H70" smd circle
			(at 30.230064 -31.139892 180)
			(size 0.450088 0.450088)
			(layers "F.Cu" "F.Mask" "F.Paste")
			(net "M_E_CPU1_SA_DQS_DN<0>")
		)
		(pad "H71" smd circle
			(at 31.170118 -31.139892 180)
			(size 0.450088 0.450088)
			(layers "F.Cu" "F.Mask" "F.Paste")
			(net "PVDDIO_P1")
		)
		(pad "H72" smd circle
			(at 32.109918 -31.139892 180)
			(size 0.450088 0.450088)
			(layers "F.Cu" "F.Mask" "F.Paste")
			(net "M_A_CPU1_SA_DQS_DN<5>")
		)
		(pad "H73" smd circle
			(at 33.049972 -31.139892 180)
			(size 0.450088 0.450088)
			(layers "F.Cu" "F.Mask" "F.Paste")
			(net "GND")
		)
		(pad "H74" smd circle
			(at 33.990026 -31.139892 180)
			(size 0.450088 0.450088)
			(layers "F.Cu" "F.Mask" "F.Paste")
			(net "M_A_CPU1_SA_DQS_DN<0>")
		)
		(pad "J1" smd circle
			(at -34.159952 -30.329886 180)
			(size 0.450088 0.450088)
			(layers "F.Cu" "F.Mask" "F.Paste")
			(net "GND")
		)
		(pad "J2" smd circle
			(at -33.219898 -30.329886 180)
			(size 0.450088 0.450088)
			(layers "F.Cu" "F.Mask" "F.Paste")
			(net "M_G_CPU1_SA_DQ<4>")
		)
		(pad "J3" smd circle
			(at -32.280098 -30.329886 180)
			(size 0.450088 0.450088)
			(layers "F.Cu" "F.Mask" "F.Paste")
			(net "M_G_CPU1_SA_DQS_DP<5>")
		)
		(pad "J4" smd circle
			(at -31.340044 -30.329886 180)
			(size 0.450088 0.450088)
			(layers "F.Cu" "F.Mask" "F.Paste")
			(net "GND")
		)
		(pad "J5" smd circle
			(at -30.39999 -30.329886 180)
			(size 0.450088 0.450088)
			(layers "F.Cu" "F.Mask" "F.Paste")
			(net "M_K_CPU1_SA_DQ<4>")
		)
		(pad "J6" smd circle
			(at -29.459936 -30.329886 180)
			(size 0.450088 0.450088)
			(layers "F.Cu" "F.Mask" "F.Paste")
			(net "GND")
		)
		(pad "J7" smd circle
			(at -28.519882 -30.329886 180)
			(size 0.450088 0.450088)
			(layers "F.Cu" "F.Mask" "F.Paste")
			(net "M_K_CPU1_SA_DQS_DP<5>")
		)
		(pad "J8" smd circle
			(at -27.580082 -30.329886 180)
			(size 0.450088 0.450088)
			(layers "F.Cu" "F.Mask" "F.Paste")
			(net "GND")
		)
		(pad "J9" smd circle
			(at -26.640028 -30.329886 180)
			(size 0.450088 0.450088)
			(layers "F.Cu" "F.Mask" "F.Paste")
			(net "M_L_CPU1_SA_DQ<4>")
		)
		(pad "J10" smd circle
			(at -25.699974 -30.329886 180)
			(size 0.450088 0.450088)
			(layers "F.Cu" "F.Mask" "F.Paste")
			(net "M_L_CPU1_SA_DQS_DP<5>")
		)
		(pad "J11" smd circle
			(at -24.75992 -30.329886 180)
			(size 0.450088 0.450088)
			(layers "F.Cu" "F.Mask" "F.Paste")
			(net "GND")
		)
		(pad "J12" smd circle
			(at -23.82012 -30.329886 180)
			(size 0.450088 0.450088)
			(layers "F.Cu" "F.Mask" "F.Paste")
			(net "M_H_CPU1_SA_DQ<4>")
		)
		(pad "J13" smd circle
			(at -22.880066 -30.329886 180)
			(size 0.450088 0.450088)
			(layers "F.Cu" "F.Mask" "F.Paste")
			(net "GND")
		)
		(pad "J14" smd circle
			(at -21.940012 -30.329886 180)
			(size 0.450088 0.450088)
			(layers "F.Cu" "F.Mask" "F.Paste")
			(net "M_H_CPU1_SA_DQS_DP<5>")
		)
		(pad "J15" smd circle
			(at -20.999958 -30.329886 180)
			(size 0.450088 0.450088)
			(layers "F.Cu" "F.Mask" "F.Paste")
			(net "GND")
		)
		(pad "J16" smd circle
			(at -20.059904 -30.329886 180)
			(size 0.450088 0.450088)
			(layers "F.Cu" "F.Mask" "F.Paste")
			(net "M_J_CPU1_SA_DQ<4>")
		)
		(pad "J17" smd circle
			(at -19.120104 -30.329886 180)
			(size 0.450088 0.450088)
			(layers "F.Cu" "F.Mask" "F.Paste")
			(net "M_J_CPU1_SA_DQS_DP<5>")
		)
		(pad "J18" smd circle
			(at -18.18005 -30.329886 180)
			(size 0.450088 0.450088)
			(layers "F.Cu" "F.Mask" "F.Paste")
			(net "GND")
		)
		(pad "J19" smd circle
			(at -17.239996 -30.329886 180)
			(size 0.450088 0.450088)
			(layers "F.Cu" "F.Mask" "F.Paste")
			(net "M_I_CPU1_SA_DQ<4>")
		)
		(pad "J20" smd circle
			(at -16.299942 -30.329886 180)
			(size 0.450088 0.450088)
			(layers "F.Cu" "F.Mask" "F.Paste")
			(net "GND")
		)
		(pad "J21" smd circle
			(at -15.359888 -30.329886 180)
			(size 0.450088 0.450088)
			(layers "F.Cu" "F.Mask" "F.Paste")
			(net "M_I_CPU1_SA_DQS_DP<5>")
		)
		(pad "J22" smd circle
			(at -14.420088 -30.329886 180)
			(size 0.450088 0.450088)
			(layers "F.Cu" "F.Mask" "F.Paste")
			(net "GND")
		)
		(pad "J23" smd circle
			(at -13.480034 -30.329886 180)
			(size 0.450088 0.450088)
			(layers "F.Cu" "F.Mask" "F.Paste")
			(net "GMI_CPU1_G2_CPU0_G0_TX_DP<14>")
		)
		(pad "J24" smd circle
			(at -12.53998 -30.329886 180)
			(size 0.450088 0.450088)
			(layers "F.Cu" "F.Mask" "F.Paste")
			(net "GMI_CPU1_G2_CPU0_G0_TX_DN<14>")
		)
		(pad "J25" smd circle
			(at -11.599926 -30.329886 180)
			(size 0.450088 0.450088)
			(layers "F.Cu" "F.Mask" "F.Paste")
			(net "GND")
		)
		(pad "J26" smd circle
			(at -10.659872 -30.329886 180)
			(size 0.450088 0.450088)
			(layers "F.Cu" "F.Mask" "F.Paste")
			(net "GMI_CPU1_G2_CPU0_G0_TX_DP<11>")
		)
		(pad "J27" smd circle
			(at -9.720072 -30.329886 180)
			(size 0.450088 0.450088)
			(layers "F.Cu" "F.Mask" "F.Paste")
			(net "GMI_CPU1_G2_CPU0_G0_TX_DN<11>")
		)
		(pad "J28" smd circle
			(at -8.780018 -30.329886 180)
			(size 0.450088 0.450088)
			(layers "F.Cu" "F.Mask" "F.Paste")
			(net "GND")
		)
		(pad "J29" smd circle
			(at -7.839964 -30.329886 180)
			(size 0.450088 0.450088)
			(layers "F.Cu" "F.Mask" "F.Paste")
			(net "GMI_CPU1_G2_CPU0_G0_TX_DP<8>")
		)
		(pad "J30" smd circle
			(at -6.89991 -30.329886 180)
			(size 0.450088 0.450088)
			(layers "F.Cu" "F.Mask" "F.Paste")
			(net "GMI_CPU1_G2_CPU0_G0_TX_DN<8>")
		)
		(pad "J31" smd circle
			(at -5.96011 -30.329886 180)
			(size 0.450088 0.450088)
			(layers "F.Cu" "F.Mask" "F.Paste")
			(net "GND")
		)
		(pad "J32" smd circle
			(at -5.020056 -30.329886 180)
			(size 0.450088 0.450088)
			(layers "F.Cu" "F.Mask" "F.Paste")
			(net "GMI_CPU1_G2_CPU0_G0_TX_DP<5>")
		)
		(pad "J33" smd circle
			(at -4.080002 -30.329886 180)
			(size 0.450088 0.450088)
			(layers "F.Cu" "F.Mask" "F.Paste")
			(net "GMI_CPU1_G2_CPU0_G0_TX_DN<5>")
		)
		(pad "J34" smd circle
			(at -3.139948 -30.329886 180)
			(size 0.450088 0.450088)
			(layers "F.Cu" "F.Mask" "F.Paste")
			(net "GND")
		)
		(pad "J35" smd circle
			(at -2.199894 -30.329886 180)
			(size 0.450088 0.450088)
			(layers "F.Cu" "F.Mask" "F.Paste")
			(net "PVDDCR_CPU0_P1")
		)
		(pad "J36" smd circle
			(at -1.260094 -30.329886 180)
			(size 0.450088 0.450088)
			(layers "F.Cu" "F.Mask" "F.Paste")
			(net "PVDDCR_CPU0_P1")
		)
		(pad "J40" smd circle
			(at 1.560068 -30.329886 180)
			(size 0.450088 0.450088)
			(layers "F.Cu" "F.Mask" "F.Paste")
			(net "PVDDCR_CPU0_P1")
		)
		(pad "J41" smd circle
			(at 2.500122 -30.329886 180)
			(size 0.450088 0.450088)
			(layers "F.Cu" "F.Mask" "F.Paste")
			(net "PVDDCR_CPU0_P1")
		)
		(pad "J42" smd circle
			(at 3.439922 -30.329886 180)
			(size 0.450088 0.450088)
			(layers "F.Cu" "F.Mask" "F.Paste")
			(net "GND")
		)
		(pad "J43" smd circle
			(at 4.379976 -30.329886 180)
			(size 0.450088 0.450088)
			(layers "F.Cu" "F.Mask" "F.Paste")
			(net "GMI_CPU0_G2_CPU1_G0_TX_DN<10>")
		)
		(pad "J44" smd circle
			(at 5.32003 -30.329886 180)
			(size 0.450088 0.450088)
			(layers "F.Cu" "F.Mask" "F.Paste")
			(net "GMI_CPU0_G2_CPU1_G0_TX_DP<10>")
		)
		(pad "J45" smd circle
			(at 6.260084 -30.329886 180)
			(size 0.450088 0.450088)
			(layers "F.Cu" "F.Mask" "F.Paste")
			(net "GND")
		)
		(pad "J46" smd circle
			(at 7.199884 -30.329886 180)
			(size 0.450088 0.450088)
			(layers "F.Cu" "F.Mask" "F.Paste")
			(net "GMI_CPU0_G2_CPU1_G0_TX_DN<7>")
		)
		(pad "J47" smd circle
			(at 8.139938 -30.329886 180)
			(size 0.450088 0.450088)
			(layers "F.Cu" "F.Mask" "F.Paste")
			(net "GMI_CPU0_G2_CPU1_G0_TX_DP<7>")
		)
		(pad "J48" smd circle
			(at 9.079992 -30.329886 180)
			(size 0.450088 0.450088)
			(layers "F.Cu" "F.Mask" "F.Paste")
			(net "GND")
		)
		(pad "J49" smd circle
			(at 10.020046 -30.329886 180)
			(size 0.450088 0.450088)
			(layers "F.Cu" "F.Mask" "F.Paste")
			(net "GMI_CPU0_G2_CPU1_G0_TX_DN<4>")
		)
		(pad "J50" smd circle
			(at 10.9601 -30.329886 180)
			(size 0.450088 0.450088)
			(layers "F.Cu" "F.Mask" "F.Paste")
			(net "GMI_CPU0_G2_CPU1_G0_TX_DP<4>")
		)
		(pad "J51" smd circle
			(at 11.8999 -30.329886 180)
			(size 0.450088 0.450088)
			(layers "F.Cu" "F.Mask" "F.Paste")
			(net "GND")
		)
		(pad "J52" smd circle
			(at 12.839954 -30.329886 180)
			(size 0.450088 0.450088)
			(layers "F.Cu" "F.Mask" "F.Paste")
			(net "GMI_CPU0_G2_CPU1_G0_TX_DN<1>")
		)
		(pad "J53" smd circle
			(at 13.780008 -30.329886 180)
			(size 0.450088 0.450088)
			(layers "F.Cu" "F.Mask" "F.Paste")
			(net "GMI_CPU0_G2_CPU1_G0_TX_DP<1>")
		)
		(pad "J54" smd circle
			(at 14.720062 -30.329886 180)
			(size 0.450088 0.450088)
			(layers "F.Cu" "F.Mask" "F.Paste")
			(net "GND")
		)
		(pad "J55" smd circle
			(at 15.660116 -30.329886 180)
			(size 0.450088 0.450088)
			(layers "F.Cu" "F.Mask" "F.Paste")
			(net "M_C_CPU1_SA_DQS_DP<5>")
		)
		(pad "J56" smd circle
			(at 16.599916 -30.329886 180)
			(size 0.450088 0.450088)
			(layers "F.Cu" "F.Mask" "F.Paste")
			(net "GND")
		)
		(pad "J57" smd circle
			(at 17.53997 -30.329886 180)
			(size 0.450088 0.450088)
			(layers "F.Cu" "F.Mask" "F.Paste")
			(net "M_C_CPU1_SA_DQ<4>")
		)
		(pad "J58" smd circle
			(at 18.480024 -30.329886 180)
			(size 0.450088 0.450088)
			(layers "F.Cu" "F.Mask" "F.Paste")
			(net "GND")
		)
		(pad "J59" smd circle
			(at 19.420078 -30.329886 180)
			(size 0.450088 0.450088)
			(layers "F.Cu" "F.Mask" "F.Paste")
			(net "M_D_CPU1_SA_DQS_DP<5>")
		)
		(pad "J60" smd circle
			(at 20.359878 -30.329886 180)
			(size 0.450088 0.450088)
			(layers "F.Cu" "F.Mask" "F.Paste")
			(net "M_D_CPU1_SA_DQ<4>")
		)
		(pad "J61" smd circle
			(at 21.299932 -30.329886 180)
			(size 0.450088 0.450088)
			(layers "F.Cu" "F.Mask" "F.Paste")
			(net "GND")
		)
		(pad "J62" smd circle
			(at 22.239986 -30.329886 180)
			(size 0.450088 0.450088)
			(layers "F.Cu" "F.Mask" "F.Paste")
			(net "M_B_CPU1_SA_DQS_DP<5>")
		)
		(pad "J63" smd circle
			(at 23.18004 -30.329886 180)
			(size 0.450088 0.450088)
			(layers "F.Cu" "F.Mask" "F.Paste")
			(net "GND")
		)
		(pad "J64" smd circle
			(at 24.120094 -30.329886 180)
			(size 0.450088 0.450088)
			(layers "F.Cu" "F.Mask" "F.Paste")
			(net "M_B_CPU1_SA_DQ<4>")
		)
		(pad "J65" smd circle
			(at 25.059894 -30.329886 180)
			(size 0.450088 0.450088)
			(layers "F.Cu" "F.Mask" "F.Paste")
			(net "GND")
		)
		(pad "J66" smd circle
			(at 25.999948 -30.329886 180)
			(size 0.450088 0.450088)
			(layers "F.Cu" "F.Mask" "F.Paste")
			(net "M_F_CPU1_SA_DQS_DP<5>")
		)
		(pad "J67" smd circle
			(at 26.940002 -30.329886 180)
			(size 0.450088 0.450088)
			(layers "F.Cu" "F.Mask" "F.Paste")
			(net "M_F_CPU1_SA_DQ<4>")
		)
		(pad "J68" smd circle
			(at 27.880056 -30.329886 180)
			(size 0.450088 0.450088)
			(layers "F.Cu" "F.Mask" "F.Paste")
			(net "GND")
		)
		(pad "J69" smd circle
			(at 28.82011 -30.329886 180)
			(size 0.450088 0.450088)
			(layers "F.Cu" "F.Mask" "F.Paste")
			(net "M_E_CPU1_SA_DQS_DP<5>")
		)
		(pad "J70" smd circle
			(at 29.75991 -30.329886 180)
			(size 0.450088 0.450088)
			(layers "F.Cu" "F.Mask" "F.Paste")
			(net "GND")
		)
		(pad "J71" smd circle
			(at 30.699964 -30.329886 180)
			(size 0.450088 0.450088)
			(layers "F.Cu" "F.Mask" "F.Paste")
			(net "M_E_CPU1_SA_DQ<4>")
		)
		(pad "J72" smd circle
			(at 31.640018 -30.329886 180)
			(size 0.450088 0.450088)
			(layers "F.Cu" "F.Mask" "F.Paste")
			(net "GND")
		)
		(pad "J73" smd circle
			(at 32.580072 -30.329886 180)
			(size 0.450088 0.450088)
			(layers "F.Cu" "F.Mask" "F.Paste")
			(net "M_A_CPU1_SA_DQS_DP<5>")
		)
		(pad "J74" smd circle
			(at 33.519872 -30.329886 180)
			(size 0.450088 0.450088)
			(layers "F.Cu" "F.Mask" "F.Paste")
			(net "M_A_CPU1_SA_DQ<4>")
		)
		(pad "J75" smd circle
			(at 34.459926 -30.329886 180)
			(size 0.450088 0.450088)
			(layers "F.Cu" "F.Mask" "F.Paste")
			(net "GND")
		)
		(pad "K2" smd circle
			(at -33.690052 -29.51988 180)
			(size 0.450088 0.450088)
			(layers "F.Cu" "F.Mask" "F.Paste")
			(net "M_G_CPU1_SA_DQ<6>")
		)
		(pad "K3" smd circle
			(at -32.749998 -29.51988 180)
			(size 0.450088 0.450088)
			(layers "F.Cu" "F.Mask" "F.Paste")
			(net "GND")
		)
		(pad "K4" smd circle
			(at -31.809944 -29.51988 180)
			(size 0.450088 0.450088)
			(layers "F.Cu" "F.Mask" "F.Paste")
			(net "M_G_CPU1_SA_DQ<5>")
		)
		(pad "K5" smd circle
			(at -30.86989 -29.51988 180)
			(size 0.450088 0.450088)
			(layers "F.Cu" "F.Mask" "F.Paste")
			(net "GND")
		)
		(pad "K6" smd circle
			(at -29.93009 -29.51988 180)
			(size 0.450088 0.450088)
			(layers "F.Cu" "F.Mask" "F.Paste")
			(net "M_K_CPU1_SA_DQ<6>")
		)
		(pad "K7" smd circle
			(at -28.990036 -29.51988 180)
			(size 0.450088 0.450088)
			(layers "F.Cu" "F.Mask" "F.Paste")
			(net "M_K_CPU1_SA_DQ<5>")
		)
		(pad "K8" smd circle
			(at -28.049982 -29.51988 180)
			(size 0.450088 0.450088)
			(layers "F.Cu" "F.Mask" "F.Paste")
			(net "GND")
		)
		(pad "K9" smd circle
			(at -27.109928 -29.51988 180)
			(size 0.450088 0.450088)
			(layers "F.Cu" "F.Mask" "F.Paste")
			(net "M_L_CPU1_SA_DQ<6>")
		)
		(pad "K10" smd circle
			(at -26.170128 -29.51988 180)
			(size 0.450088 0.450088)
			(layers "F.Cu" "F.Mask" "F.Paste")
			(net "GND")
		)
		(pad "K11" smd circle
			(at -25.230074 -29.51988 180)
			(size 0.450088 0.450088)
			(layers "F.Cu" "F.Mask" "F.Paste")
			(net "M_L_CPU1_SA_DQ<5>")
		)
		(pad "K12" smd circle
			(at -24.29002 -29.51988 180)
			(size 0.450088 0.450088)
			(layers "F.Cu" "F.Mask" "F.Paste")
			(net "GND")
		)
		(pad "K13" smd circle
			(at -23.349966 -29.51988 180)
			(size 0.450088 0.450088)
			(layers "F.Cu" "F.Mask" "F.Paste")
			(net "M_H_CPU1_SA_DQ<6>")
		)
		(pad "K14" smd circle
			(at -22.409912 -29.51988 180)
			(size 0.450088 0.450088)
			(layers "F.Cu" "F.Mask" "F.Paste")
			(net "M_H_CPU1_SA_DQ<5>")
		)
		(pad "K15" smd circle
			(at -21.470112 -29.51988 180)
			(size 0.450088 0.450088)
			(layers "F.Cu" "F.Mask" "F.Paste")
			(net "GND")
		)
		(pad "K16" smd circle
			(at -20.530058 -29.51988 180)
			(size 0.450088 0.450088)
			(layers "F.Cu" "F.Mask" "F.Paste")
			(net "M_J_CPU1_SA_DQ<6>")
		)
		(pad "K17" smd circle
			(at -19.590004 -29.51988 180)
			(size 0.450088 0.450088)
			(layers "F.Cu" "F.Mask" "F.Paste")
			(net "GND")
		)
		(pad "K18" smd circle
			(at -18.64995 -29.51988 180)
			(size 0.450088 0.450088)
			(layers "F.Cu" "F.Mask" "F.Paste")
			(net "M_J_CPU1_SA_DQ<5>")
		)
		(pad "K19" smd circle
			(at -17.709896 -29.51988 180)
			(size 0.450088 0.450088)
			(layers "F.Cu" "F.Mask" "F.Paste")
			(net "GND")
		)
		(pad "K20" smd circle
			(at -16.770096 -29.51988 180)
			(size 0.450088 0.450088)
			(layers "F.Cu" "F.Mask" "F.Paste")
			(net "M_I_CPU1_SA_DQ<6>")
		)
		(pad "K21" smd circle
			(at -15.830042 -29.51988 180)
			(size 0.450088 0.450088)
			(layers "F.Cu" "F.Mask" "F.Paste")
			(net "M_I_CPU1_SA_DQ<5>")
		)
		(pad "K22" smd circle
			(at -14.889988 -29.51988 180)
			(size 0.450088 0.450088)
			(layers "F.Cu" "F.Mask" "F.Paste")
			(net "PVDDCR_SOC_P1")
		)
		(pad "K23" smd circle
			(at -13.949934 -29.51988 180)
			(size 0.450088 0.450088)
			(layers "F.Cu" "F.Mask" "F.Paste")
			(net "GND")
		)
		(pad "K24" smd circle
			(at -13.00988 -29.51988 180)
			(size 0.450088 0.450088)
			(layers "F.Cu" "F.Mask" "F.Paste")
			(net "GND")
		)
		(pad "K25" smd circle
			(at -12.07008 -29.51988 180)
			(size 0.450088 0.450088)
			(layers "F.Cu" "F.Mask" "F.Paste")
			(net "GND")
		)
		(pad "K26" smd circle
			(at -11.130026 -29.51988 180)
			(size 0.450088 0.450088)
			(layers "F.Cu" "F.Mask" "F.Paste")
			(net "GND")
		)
		(pad "K27" smd circle
			(at -10.189972 -29.51988 180)
			(size 0.450088 0.450088)
			(layers "F.Cu" "F.Mask" "F.Paste")
			(net "GND")
		)
		(pad "K28" smd circle
			(at -9.249918 -29.51988 180)
			(size 0.450088 0.450088)
			(layers "F.Cu" "F.Mask" "F.Paste")
			(net "GND")
		)
		(pad "K29" smd circle
			(at -8.310118 -29.51988 180)
			(size 0.450088 0.450088)
			(layers "F.Cu" "F.Mask" "F.Paste")
			(net "GND")
		)
		(pad "K30" smd circle
			(at -7.370064 -29.51988 180)
			(size 0.450088 0.450088)
			(layers "F.Cu" "F.Mask" "F.Paste")
			(net "GND")
		)
		(pad "K31" smd circle
			(at -6.43001 -29.51988 180)
			(size 0.450088 0.450088)
			(layers "F.Cu" "F.Mask" "F.Paste")
			(net "GND")
		)
	)
)
